# S9S_MB_2U (Grand Teton) — schematic netlist excerpt (pin names and nets, part order shuffled) for the footprints in the layout excerpt that follows; sources: Cadence DE-HDL packaged netlist, KiCad conversion of 03242023_DA0F0TMBIJ0_F0T_Motherboard_J_brd_V01_OCP.brd

R3725  Q_RES  2.2K 5% CHIP  pkg 0402LF  page 233 : A = P3V3_AUX ; B = SMB_LM75_0_3V3AUX_SCL
C404  Q_CAP  22UF 4V 20% X6S  pkg C0402  page 74 : A = PVCCFA_EHV_FIVRA_CPU0 ; B = GND

(kicad_pcb
	(version 20260206)
	(generator "pcbnew")
	(generator_version "10.0")
	(general
		(thickness 1.6)
		(legacy_teardrops no)
	)
	(paper "A4")
	(title_block
		(title "03242023_DA0F0TMBIJ0_F0T_Motherboard_J_brd_V01_OCP.brd")
		(comment 1 "Grand Teton / footprints 1860-1861 of 6105")
	)
	(layers
		(0 "F.Cu" signal "TOP")
		(4 "In1.Cu" signal "GND")
		(6 "In2.Cu" signal "IN1")
		(8 "In3.Cu" signal "GND1")
		(10 "In4.Cu" signal "IN2")
		(12 "In5.Cu" signal "GND2")
		(14 "In6.Cu" signal "IN3")
		(16 "In7.Cu" signal "GND3")
		(18 "In8.Cu" signal "VCC")
		(20 "In9.Cu" signal "VCC1")
		(22 "In10.Cu" signal "GND4")
		(24 "In11.Cu" signal "IN4")
		(26 "In12.Cu" signal "GND5")
		(28 "In13.Cu" signal "IN5")
		(30 "In14.Cu" signal "GND6")
		(32 "In15.Cu" signal "IN6")
		(34 "In16.Cu" signal "GND7")
		(2 "B.Cu" signal "BOTTOM")
		(9 "F.Adhes" user "F.Adhesive")
		(11 "B.Adhes" user "B.Adhesive")
		(13 "F.Paste" user "Package Geometry/Pastemask Top")
		(15 "B.Paste" user "Package Geometry/Pastemask Bottom")
		(5 "F.SilkS" user "Ref Des/Silkscreen Top")
		(7 "B.SilkS" user "Ref Des/Silkscreen Bottom")
		(1 "F.Mask" user "Board Geometry/Soldermask Top")
		(3 "B.Mask" user "Board Geometry/Soldermask Bottom")
		(17 "Dwgs.User" user "User.Drawings")
		(19 "Cmts.User" user "User.Comments")
		(21 "Eco1.User" user "User.Eco1")
		(23 "Eco2.User" user "User.Eco2")
		(25 "Edge.Cuts" user "Board Geometry/Outline")
		(27 "Margin" user)
		(31 "F.CrtYd" user "Package Geometry/Place Bound Top")
		(29 "B.CrtYd" user "Package Geometry/Place Bound Bottom")
		(35 "F.Fab" user "Ref Des/Assembly Top")
		(33 "B.Fab" user "Ref Des/Assembly Bottom")
	)
	(footprint ""
		(layer "F.Cu")
		(at 367.44783 -240.276888 90)
		(property "Reference" "C404"
			(at 0 0 90)
			(layer "F.SilkS")
			(hide yes)
			(effects
				(font
					(size 1.27 1.27)
				)
			)
		)
		(property "Value" ""
			(at 0 0 90)
			(layer "F.Fab")
			(effects
				(font
					(size 1.27 1.27)
				)
			)
		)
		(duplicate_pad_numbers_are_jumpers no)
		(fp_line
			(start 0.7874 -0.4064)
			(end 0.7874 0.4064)
			(stroke
				(width 0.1524)
				(type default)
			)
			(layer "F.SilkS")
		)
		(fp_line
			(start -0.7874 -0.4064)
			(end 0.7874 -0.4064)
			(stroke
				(width 0.1524)
				(type default)
			)
			(layer "F.SilkS")
		)
		(fp_line
			(start 0.7874 0.4064)
			(end -0.7874 0.4064)
			(stroke
				(width 0.1524)
				(type default)
			)
			(layer "F.SilkS")
		)
		(fp_line
			(start -0.7874 0.4064)
			(end -0.7874 -0.4064)
			(stroke
				(width 0.1524)
				(type default)
			)
			(layer "F.SilkS")
		)
		(fp_line
			(start -0.12065 -0.305054)
			(end -0.12065 -0.2794)
			(stroke
				(width 0.1)
				(type default)
			)
			(layer "F.Fab")
		)
		(fp_line
			(start -0.67945 -0.305054)
			(end -0.12065 -0.305054)
			(stroke
				(width 0.1)
				(type default)
			)
			(layer "F.Fab")
		)
		(fp_line
			(start 0.67945 -0.3048)
			(end 0.67945 0.3048)
			(stroke
				(width 0.1)
				(type default)
			)
			(layer "F.Fab")
		)
		(fp_line
			(start 0.12065 -0.3048)
			(end 0.67945 -0.3048)
			(stroke
				(width 0.1)
				(type default)
			)
			(layer "F.Fab")
		)
		(fp_line
			(start 0.12065 -0.2794)
			(end 0.12065 -0.3048)
			(stroke
				(width 0.1)
				(type default)
			)
			(layer "F.Fab")
		)
		(fp_line
			(start -0.12065 -0.2794)
			(end 0.12065 -0.2794)
			(stroke
				(width 0.1)
				(type default)
			)
			(layer "F.Fab")
		)
		(fp_line
			(start 0.120396 0.2794)
			(end -0.12065 0.2794)
			(stroke
				(width 0.1)
				(type default)
			)
			(layer "F.Fab")
		)
		(fp_line
			(start -0.12065 0.2794)
			(end -0.12065 0.3048)
			(stroke
				(width 0.1)
				(type default)
			)
			(layer "F.Fab")
		)
		(fp_line
			(start 0.67945 0.3048)
			(end 0.120396 0.3048)
			(stroke
				(width 0.1)
				(type default)
			)
			(layer "F.Fab")
		)
		(fp_line
			(start 0.120396 0.3048)
			(end 0.120396 0.2794)
			(stroke
				(width 0.1)
				(type default)
			)
			(layer "F.Fab")
		)
		(fp_line
			(start -0.12065 0.3048)
			(end -0.67945 0.3048)
			(stroke
				(width 0.1)
				(type default)
			)
			(layer "F.Fab")
		)
		(fp_line
			(start -0.67945 0.3048)
			(end -0.67945 -0.305054)
			(stroke
				(width 0.1)
				(type default)
			)
			(layer "F.Fab")
		)
		(pad "1" smd circle
			(at -0.40005 0 90)
			(size 0 0)
			(layers "F.Cu" "F.Mask" "F.Paste")
			(net "PVCCFA_EHV_FIVRA_CPU0")
		)
		(pad "2" smd circle
			(at 0.40005 0 90)
			(size 0 0)
			(layers "F.Cu" "F.Mask" "F.Paste")
			(net "GND")
		)
	)
	(footprint ""
		(layer "F.Cu")
		(at 51.593496 -110.93577)
		(property "Reference" "R3725"
			(at 0 0 0)
			(layer "F.SilkS")
			(hide yes)
			(effects
				(font
					(size 1.27 1.27)
				)
			)
		)
		(property "Value" ""
			(at 0 0 0)
			(layer "F.Fab")
			(effects
				(font
					(size 1.27 1.27)
				)
			)
		)
		(duplicate_pad_numbers_are_jumpers no)
		(fp_line
			(start -0.7874 -0.4064)
			(end 0.7874 -0.4064)
			(stroke
				(width 0.1524)
				(type default)
			)
			(layer "F.SilkS")
		)
		(fp_line
			(start -0.7874 0.4064)
			(end -0.7874 -0.4064)
			(stroke
				(width 0.1524)
				(type default)
			)
			(layer "F.SilkS")
		)
		(fp_line
			(start 0.7874 -0.4064)
			(end 0.7874 0.4064)
			(stroke
				(width 0.1524)
				(type default)
			)
			(layer "F.SilkS")
		)
		(fp_line
			(start 0.7874 0.4064)
			(end -0.7874 0.4064)
			(stroke
				(width 0.1524)
				(type default)
			)
			(layer "F.SilkS")
		)
		(fp_line
			(start -0.67945 -0.305054)
			(end -0.12065 -0.305054)
			(stroke
				(width 0.1)
				(type default)
			)
			(layer "F.Fab")
		)
		(fp_line
			(start -0.67945 0.3048)
			(end -0.67945 -0.305054)
			(stroke
				(width 0.1)
				(type default)
			)
			(layer "F.Fab")
		)
		(fp_line
			(start -0.12065 -0.305054)
			(end -0.12065 -0.2794)
			(stroke
				(width 0.1)
				(type default)
			)
			(layer "F.Fab")
		)
		(fp_line
			(start -0.12065 -0.2794)
			(end 0.12065 -0.2794)
			(stroke
				(width 0.1)
				(type default)
			)
			(layer "F.Fab")
		)
		(fp_line
			(start -0.12065 0.2794)
			(end -0.12065 0.3048)
			(stroke
				(width 0.1)
				(type default)
			)
			(layer "F.Fab")
		)
		(fp_line
			(start -0.12065 0.3048)
			(end -0.67945 0.3048)
			(stroke
				(width 0.1)
				(type default)
			)
			(layer "F.Fab")
		)
		(fp_line
			(start 0.120396 0.2794)
			(end -0.12065 0.2794)
			(stroke
				(width 0.1)
				(type default)
			)
			(layer "F.Fab")
		)
		(fp_line
			(start 0.120396 0.3048)
			(end 0.120396 0.2794)
			(stroke
				(width 0.1)
				(type default)
			)
			(layer "F.Fab")
		)
		(fp_line
			(start 0.12065 -0.3048)
			(end 0.67945 -0.3048)
			(stroke
				(width 0.1)
				(type default)
			)
			(layer "F.Fab")
		)
		(fp_line
			(start 0.12065 -0.2794)
			(end 0.12065 -0.3048)
			(stroke
				(width 0.1)
				(type default)
			)
			(layer "F.Fab")
		)
		(fp_line
			(start 0.67945 -0.3048)
			(end 0.67945 0.3048)
			(stroke
				(width 0.1)
				(type default)
			)
			(layer "F.Fab")
		)
		(fp_line
			(start 0.67945 0.3048)
			(end 0.120396 0.3048)
			(stroke
				(width 0.1)
				(type default)
			)
			(layer "F.Fab")
		)
		(pad "1" smd circle
			(at -0.40005 0)
			(size 0 0)
			(layers "F.Cu" "F.Mask" "F.Paste")
			(net "P3V3_AUX")
		)
		(pad "2" smd circle
			(at 0.40005 0)
			(size 0 0)
			(layers "F.Cu" "F.Mask" "F.Paste")
			(net "SMB_LM75_0_3V3AUX_SCL")
		)
	)
)
